(kicad_pcb
	(version 20260206)
	(generator "pcbnew")
	(generator_version "10.0")
	(general
		(thickness 1.6)
		(legacy_teardrops no)
	)
	(paper "A4")
	(title_block
		(title "v1-chassis-manager — T6M_CM_d_v01_1031_1645.brd")
		(comment 1 "Open CloudServer (Microsoft) / footprints 815-820 of 2512")
	)
	(layers
		(0 "F.Cu" signal "TOP")
		(4 "In1.Cu" signal "GND1")
		(6 "In2.Cu" signal "IN1")
		(8 "In3.Cu" signal "VCC1")
		(10 "In4.Cu" signal "VCC2")
		(12 "In5.Cu" signal "GND2")
		(14 "In6.Cu" signal "IN2")
		(16 "In7.Cu" signal "IN3")
		(18 "In8.Cu" signal "GND3")
		(2 "B.Cu" signal "BOTTOM")
		(9 "F.Adhes" user "F.Adhesive")
		(11 "B.Adhes" user "B.Adhesive")
		(13 "F.Paste" user "Package Geometry/Pastemask Top")
		(15 "B.Paste" user "Package Geometry/Pastemask Bottom")
		(5 "F.SilkS" user "Ref Des/Silkscreen Top")
		(7 "B.SilkS" user "Ref Des/Silkscreen Bottom")
		(1 "F.Mask" user "Board Geometry/Soldermask Top")
		(3 "B.Mask" user "Board Geometry/Soldermask Bottom")
		(17 "Dwgs.User" user "User.Drawings")
		(19 "Cmts.User" user "User.Comments")
		(21 "Eco1.User" user "User.Eco1")
		(23 "Eco2.User" user "User.Eco2")
		(25 "Edge.Cuts" user "Board Geometry/Outline")
		(27 "Margin" user)
		(31 "F.CrtYd" user "Package Geometry/Place Bound Top")
		(29 "B.CrtYd" user "Package Geometry/Place Bound Bottom")
		(35 "F.Fab" user "Ref Des/Assembly Top")
		(33 "B.Fab" user "Ref Des/Assembly Bottom")
	)
	(footprint ""
		(layer "F.Cu")
		(at 8.73379 -167.373554 180)
		(property "Reference" "C548"
			(at 0.84074 1.497076 0)
			(unlocked yes)
			(layer "F.SilkS")
			(effects
				(font
					(size 0.7874 0.5842)
					(thickness 0.1524)
				)
				(justify left)
			)
		)
		(property "Value" ""
			(at 0 0 180)
			(layer "F.Fab")
			(effects
				(font
					(size 1.27 1.27)
				)
			)
		)
		(duplicate_pad_numbers_are_jumpers no)
		(fp_line
			(start 0.7874 0.4064)
			(end -0.7874 0.4064)
			(stroke
				(width 0.1524)
				(type default)
			)
			(layer "F.SilkS")
		)
		(fp_line
			(start 0.7874 -0.4064)
			(end 0.7874 0.4064)
			(stroke
				(width 0.1524)
				(type default)
			)
			(layer "F.SilkS")
		)
		(fp_line
			(start 0 0.381)
			(end 0 -0.381)
			(stroke
				(width 0.1524)
				(type default)
			)
			(layer "F.SilkS")
		)
		(fp_line
			(start -0.7874 0.4064)
			(end -0.7874 -0.4064)
			(stroke
				(width 0.1524)
				(type default)
			)
			(layer "F.SilkS")
		)
		(fp_line
			(start -0.7874 -0.4064)
			(end 0.7874 -0.4064)
			(stroke
				(width 0.1524)
				(type default)
			)
			(layer "F.SilkS")
		)
		(fp_poly
			(pts
				(xy -0.5334 0.254) (xy -0.635 0.254) (xy -0.635 0.2286) (xy -0.635 -0.254) (xy -0.5334 -0.254) (xy -0.5334 -0.2794)
				(xy 0.5334 -0.2794) (xy 0.5334 -0.254) (xy 0.635 -0.254) (xy 0.635 0.254) (xy 0.5334 0.254) (xy 0.5334 0.2794)
				(xy -0.508 0.2794) (xy -0.5334 0.2794)
			)
			(stroke
				(width 0)
				(type default)
			)
			(fill no)
			(layer "F.CrtYd")
		)
		(pad "1" smd rect
			(at 0.40005 0 180)
			(size 0.4572 0.508)
			(layers "F.Cu" "F.Mask" "F.Paste")
			(net "GND")
		)
		(pad "2" smd rect
			(at -0.40005 0 180)
			(size 0.4572 0.508)
			(layers "F.Cu" "F.Mask" "F.Paste")
			(net "N54258537")
		)
	)
	(footprint ""
		(layer "F.Cu")
		(at 14.035024 -160.409128 -90)
		(property "Reference" "C540"
			(at 0.076708 -1.743202 90)
			(unlocked yes)
			(layer "F.SilkS")
			(effects
				(font
					(size 0.7874 0.5842)
					(thickness 0.1524)
				)
				(justify left)
			)
		)
		(property "Value" ""
			(at 0 0 270)
			(layer "F.Fab")
			(effects
				(font
					(size 1.27 1.27)
				)
			)
		)
		(duplicate_pad_numbers_are_jumpers no)
		(fp_line
			(start -2.2098 0.9398)
			(end -2.2098 -0.9398)
			(stroke
				(width 0.1524)
				(type default)
			)
			(layer "F.SilkS")
		)
		(fp_line
			(start 2.2098 0.9398)
			(end -2.2098 0.9398)
			(stroke
				(width 0.1524)
				(type default)
			)
			(layer "F.SilkS")
		)
		(fp_line
			(start -2.2098 -0.9398)
			(end 2.2098 -0.9398)
			(stroke
				(width 0.1524)
				(type default)
			)
			(layer "F.SilkS")
		)
		(fp_line
			(start 0 -0.9398)
			(end 0 0.9398)
			(stroke
				(width 0.1524)
				(type default)
			)
			(layer "F.SilkS")
		)
		(fp_line
			(start 2.2098 -0.9398)
			(end 2.2098 0.9398)
			(stroke
				(width 0.1524)
				(type default)
			)
			(layer "F.SilkS")
		)
		(fp_poly
			(pts
				(xy -1.6764 0.889) (xy -1.6764 0.7874) (xy -2.0574 0.7874) (xy -2.0574 -0.7874) (xy -1.6764 -0.7874)
				(xy -1.6764 -0.889) (xy -1.6764 -0.9398) (xy 1.6764 -0.9398) (xy 1.6764 -0.889) (xy 1.6764 -0.7874)
				(xy 2.0574 -0.7874) (xy 2.0574 0.7874) (xy 1.6764 0.7874) (xy 1.6764 0.889) (xy 1.6764 0.9398) (xy -1.6764 0.9398)
			)
			(stroke
				(width 0)
				(type default)
			)
			(fill no)
			(layer "F.CrtYd")
		)
		(pad "1" smd rect
			(at 1.4732 0 270)
			(size 1.1684 1.5748)
			(layers "F.Cu" "F.Mask" "F.Paste")
			(net "N54065132")
		)
		(pad "2" smd rect
			(at -1.4732 0 270)
			(size 1.1684 1.5748)
			(layers "F.Cu" "F.Mask" "F.Paste")
			(net "GND")
		)
	)
	(footprint ""
		(layer "F.Cu")
		(at 90.812112 -171.48302 180)
		(property "Reference" "R936"
			(at -85.974428 -74.521568 0)
			(unlocked yes)
			(layer "F.SilkS")
			(effects
				(font
					(size 0.7874 0.5842)
					(thickness 0.1524)
				)
				(justify left)
			)
		)
		(property "Value" ""
			(at 0 0 180)
			(layer "F.Fab")
			(effects
				(font
					(size 1.27 1.27)
				)
			)
		)
		(duplicate_pad_numbers_are_jumpers no)
		(fp_line
			(start 0.7874 0.4064)
			(end -0.7874 0.4064)
			(stroke
				(width 0.1524)
				(type default)
			)
			(layer "F.SilkS")
		)
		(fp_line
			(start 0.7874 -0.4064)
			(end 0.7874 0.4064)
			(stroke
				(width 0.1524)
				(type default)
			)
			(layer "F.SilkS")
		)
		(fp_line
			(start -0.7874 0.4064)
			(end -0.7874 -0.4064)
			(stroke
				(width 0.1524)
				(type default)
			)
			(layer "F.SilkS")
		)
		(fp_line
			(start -0.7874 -0.4064)
			(end 0.7874 -0.4064)
			(stroke
				(width 0.1524)
				(type default)
			)
			(layer "F.SilkS")
		)
		(fp_poly
			(pts
				(xy -0.508 0.2794) (xy -0.508 0.2286) (xy -0.635 0.2286) (xy -0.635 -0.254) (xy -0.5334 -0.254)
				(xy -0.5334 -0.2794) (xy 0.5334 -0.2794) (xy 0.5334 -0.254) (xy 0.635 -0.254) (xy 0.635 0.254) (xy 0.5334 0.254)
				(xy 0.5334 0.2794)
			)
			(stroke
				(width 0)
				(type default)
			)
			(fill no)
			(layer "F.CrtYd")
		)
		(pad "1" smd rect
			(at 0.40005 0 180)
			(size 0.4572 0.508)
			(layers "F.Cu" "F.Mask" "F.Paste")
			(net "UART_T6_NODE1_TXD")
		)
		(pad "2" smd rect
			(at -0.40005 0 180)
			(size 0.4572 0.508)
			(layers "F.Cu" "F.Mask" "F.Paste")
			(net "UART_T6_NODE1_TXD_R")
		)
	)
	(footprint ""
		(layer "F.Cu")
		(at 143.105886 -54.529228 180)
		(property "Reference" "R1015"
			(at -1.100582 0.92202 0)
			(unlocked yes)
			(layer "F.SilkS")
			(effects
				(font
					(size 0.7874 0.5842)
					(thickness 0.1524)
				)
				(justify left)
			)
		)
		(property "Value" ""
			(at 0 0 180)
			(layer "F.Fab")
			(effects
				(font
					(size 1.27 1.27)
				)
			)
		)
		(duplicate_pad_numbers_are_jumpers no)
		(fp_line
			(start 0.7874 0.4064)
			(end -0.7874 0.4064)
			(stroke
				(width 0.1524)
				(type default)
			)
			(layer "F.SilkS")
		)
		(fp_line
			(start 0.7874 -0.4064)
			(end 0.7874 0.4064)
			(stroke
				(width 0.1524)
				(type default)
			)
			(layer "F.SilkS")
		)
		(fp_line
			(start -0.7874 0.4064)
			(end -0.7874 -0.4064)
			(stroke
				(width 0.1524)
				(type default)
			)
			(layer "F.SilkS")
		)
		(fp_line
			(start -0.7874 -0.4064)
			(end 0.7874 -0.4064)
			(stroke
				(width 0.1524)
				(type default)
			)
			(layer "F.SilkS")
		)
		(fp_poly
			(pts
				(xy -0.508 0.2794) (xy -0.508 0.2286) (xy -0.635 0.2286) (xy -0.635 -0.254) (xy -0.5334 -0.254)
				(xy -0.5334 -0.2794) (xy 0.5334 -0.2794) (xy 0.5334 -0.254) (xy 0.635 -0.254) (xy 0.635 0.254) (xy 0.5334 0.254)
				(xy 0.5334 0.2794)
			)
			(stroke
				(width 0)
				(type default)
			)
			(fill no)
			(layer "F.CrtYd")
		)
		(pad "1" smd rect
			(at 0.40005 0 180)
			(size 0.4572 0.508)
			(layers "F.Cu" "F.Mask" "F.Paste")
			(net "P5V_NODE1")
		)
		(pad "2" smd rect
			(at -0.40005 0 180)
			(size 0.4572 0.508)
			(layers "F.Cu" "F.Mask" "F.Paste")
			(net "UART_DTR_P2_N")
		)
	)
	(footprint ""
		(layer "F.Cu")
		(at 156.041852 -105.98023 -90)
		(property "Reference" "R273"
			(at -1.590802 -0.01143 90)
			(unlocked yes)
			(layer "F.SilkS")
			(effects
				(font
					(size 0.7874 0.5842)
					(thickness 0.1524)
				)
				(justify left)
			)
		)
		(property "Value" ""
			(at 0 0 270)
			(layer "F.Fab")
			(effects
				(font
					(size 1.27 1.27)
				)
			)
		)
		(duplicate_pad_numbers_are_jumpers no)
		(fp_line
			(start -0.7874 0.4064)
			(end -0.7874 -0.4064)
			(stroke
				(width 0.1524)
				(type default)
			)
			(layer "F.SilkS")
		)
		(fp_line
			(start 0.7874 0.4064)
			(end -0.7874 0.4064)
			(stroke
				(width 0.1524)
				(type default)
			)
			(layer "F.SilkS")
		)
		(fp_line
			(start -0.7874 -0.4064)
			(end 0.7874 -0.4064)
			(stroke
				(width 0.1524)
				(type default)
			)
			(layer "F.SilkS")
		)
		(fp_line
			(start 0.7874 -0.4064)
			(end 0.7874 0.4064)
			(stroke
				(width 0.1524)
				(type default)
			)
			(layer "F.SilkS")
		)
		(fp_poly
			(pts
				(xy -0.508 0.2794) (xy -0.508 0.2286) (xy -0.635 0.2286) (xy -0.635 -0.254) (xy -0.5334 -0.254)
				(xy -0.5334 -0.2794) (xy 0.5334 -0.2794) (xy 0.5334 -0.254) (xy 0.635 -0.254) (xy 0.635 0.254) (xy 0.5334 0.254)
				(xy 0.5334 0.2794)
			)
			(stroke
				(width 0)
				(type default)
			)
			(fill no)
			(layer "F.CrtYd")
		)
		(pad "1" smd rect
			(at 0.40005 0 270)
			(size 0.4572 0.508)
			(layers "F.Cu" "F.Mask" "F.Paste")
			(net "PE_SW_USB_PERST_L")
		)
		(pad "2" smd rect
			(at -0.40005 0 270)
			(size 0.4572 0.508)
			(layers "F.Cu" "F.Mask" "F.Paste")
			(net "N34379705")
		)
	)
	(footprint ""
		(layer "F.Cu")
		(at 119.238776 -160.40481 90)
		(property "Reference" "R668"
			(at -0.90297 -2.14503 90)
			(unlocked yes)
			(layer "F.SilkS")
			(effects
				(font
					(size 0.635 0.4064)
					(thickness 0.1524)
				)
				(justify left)
			)
		)
		(property "Value" ""
			(at 0 0 90)
			(layer "F.Fab")
			(effects
				(font
					(size 1.27 1.27)
				)
			)
		)
		(duplicate_pad_numbers_are_jumpers no)
		(fp_line
			(start 0.7874 -0.4064)
			(end 0.7874 0.4064)
			(stroke
				(width 0.1524)
				(type default)
			)
			(layer "F.SilkS")
		)
		(fp_line
			(start -0.7874 -0.4064)
			(end 0.7874 -0.4064)
			(stroke
				(width 0.1524)
				(type default)
			)
			(layer "F.SilkS")
		)
		(fp_line
			(start 0.7874 0.4064)
			(end -0.7874 0.4064)
			(stroke
				(width 0.1524)
				(type default)
			)
			(layer "F.SilkS")
		)
		(fp_line
			(start -0.7874 0.4064)
			(end -0.7874 -0.4064)
			(stroke
				(width 0.1524)
				(type default)
			)
			(layer "F.SilkS")
		)
		(fp_poly
			(pts
				(xy -0.508 0.2794) (xy -0.508 0.2286) (xy -0.635 0.2286) (xy -0.635 -0.254) (xy -0.5334 -0.254)
				(xy -0.5334 -0.2794) (xy 0.5334 -0.2794) (xy 0.5334 -0.254) (xy 0.635 -0.254) (xy 0.635 0.254) (xy 0.5334 0.254)
				(xy 0.5334 0.2794)
			)
			(stroke
				(width 0)
				(type default)
			)
			(fill no)
			(layer "F.CrtYd")
		)
		(pad "1" smd rect
			(at 0.40005 0 90)
			(size 0.4572 0.508)
			(layers "F.Cu" "F.Mask" "F.Paste")
			(net "P3V3_NODE1")
		)
		(pad "2" smd rect
			(at -0.40005 0 90)
			(size 0.4572 0.508)
			(layers "F.Cu" "F.Mask" "F.Paste")
			(net "I2C_PSU2_SDA_MOS")
		)
	)
)
